(kicad_pcb
	(version 20260206)
	(generator "pcbnew")
	(generator_version "10.0")
	(general
		(thickness 1.6)
		(legacy_teardrops no)
	)
	(paper "A4")
	(title_block
		(title "12092022_DA0F0TMDCD0_F0T_Management_Board_D_brd_V3_OCP.brd")
		(comment 1 "Grand Teton / footprints 1386-1391 of 1440")
	)
	(layers
		(0 "F.Cu" signal "TOP")
		(4 "In1.Cu" signal "GND")
		(6 "In2.Cu" signal "IN1")
		(8 "In3.Cu" signal "GND1")
		(10 "In4.Cu" signal "IN2")
		(12 "In5.Cu" signal "VCC")
		(14 "In6.Cu" signal "VCC1")
		(16 "In7.Cu" signal "IN3")
		(18 "In8.Cu" signal "GND2")
		(20 "In9.Cu" signal "IN4")
		(22 "In10.Cu" signal "GND3")
		(2 "B.Cu" signal "BOTTOM")
		(9 "F.Adhes" user "F.Adhesive")
		(11 "B.Adhes" user "B.Adhesive")
		(13 "F.Paste" user "Package Geometry/Pastemask Top")
		(15 "B.Paste" user "Package Geometry/Pastemask Bottom")
		(5 "F.SilkS" user "Ref Des/Silkscreen Top")
		(7 "B.SilkS" user "Ref Des/Silkscreen Bottom")
		(1 "F.Mask" user "Board Geometry/Soldermask Top")
		(3 "B.Mask" user "Board Geometry/Soldermask Bottom")
		(17 "Dwgs.User" user "User.Drawings")
		(19 "Cmts.User" user "User.Comments")
		(21 "Eco1.User" user "User.Eco1")
		(23 "Eco2.User" user "User.Eco2")
		(25 "Edge.Cuts" user "Board Geometry/Outline")
		(27 "Margin" user)
		(31 "F.CrtYd" user "Package Geometry/Place Bound Top")
		(29 "B.CrtYd" user "Package Geometry/Place Bound Bottom")
		(35 "F.Fab" user "Ref Des/Assembly Top")
		(33 "B.Fab" user "Ref Des/Assembly Bottom")
	)
	(footprint ""
		(layer "B.Cu")
		(at 55.486808 -94.520766 180)
		(property "Reference" "C300"
			(at 0 0 0)
			(layer "B.SilkS")
			(hide yes)
			(effects
				(font
					(size 1.27 1.27)
				)
				(justify mirror)
			)
		)
		(property "Value" ""
			(at 0 0 0)
			(layer "B.Fab")
			(effects
				(font
					(size 1.27 1.27)
				)
				(justify mirror)
			)
		)
		(duplicate_pad_numbers_are_jumpers no)
		(fp_line
			(start 0.7874 0.4064)
			(end 0.7874 -0.4064)
			(stroke
				(width 0.1524)
				(type default)
			)
			(layer "B.SilkS")
		)
		(fp_line
			(start 0.7874 -0.4064)
			(end -0.7874 -0.4064)
			(stroke
				(width 0.1524)
				(type default)
			)
			(layer "B.SilkS")
		)
		(fp_line
			(start -0.7874 0.4064)
			(end 0.7874 0.4064)
			(stroke
				(width 0.1524)
				(type default)
			)
			(layer "B.SilkS")
		)
		(fp_line
			(start -0.7874 -0.4064)
			(end -0.7874 0.4064)
			(stroke
				(width 0.1524)
				(type default)
			)
			(layer "B.SilkS")
		)
		(fp_line
			(start 0.67945 0.3048)
			(end 0.67945 -0.305054)
			(stroke
				(width 0.1)
				(type default)
			)
			(layer "B.Fab")
		)
		(fp_line
			(start 0.67945 -0.305054)
			(end 0.12065 -0.305054)
			(stroke
				(width 0.1)
				(type default)
			)
			(layer "B.Fab")
		)
		(fp_line
			(start 0.12065 0.3048)
			(end 0.67945 0.3048)
			(stroke
				(width 0.1)
				(type default)
			)
			(layer "B.Fab")
		)
		(fp_line
			(start 0.12065 0.2794)
			(end 0.12065 0.3048)
			(stroke
				(width 0.1)
				(type default)
			)
			(layer "B.Fab")
		)
		(fp_line
			(start 0.12065 -0.2794)
			(end -0.12065 -0.2794)
			(stroke
				(width 0.1)
				(type default)
			)
			(layer "B.Fab")
		)
		(fp_line
			(start 0.12065 -0.305054)
			(end 0.12065 -0.2794)
			(stroke
				(width 0.1)
				(type default)
			)
			(layer "B.Fab")
		)
		(fp_line
			(start -0.120396 0.3048)
			(end -0.120396 0.2794)
			(stroke
				(width 0.1)
				(type default)
			)
			(layer "B.Fab")
		)
		(fp_line
			(start -0.120396 0.2794)
			(end 0.12065 0.2794)
			(stroke
				(width 0.1)
				(type default)
			)
			(layer "B.Fab")
		)
		(fp_line
			(start -0.12065 -0.2794)
			(end -0.12065 -0.3048)
			(stroke
				(width 0.1)
				(type default)
			)
			(layer "B.Fab")
		)
		(fp_line
			(start -0.12065 -0.3048)
			(end -0.67945 -0.3048)
			(stroke
				(width 0.1)
				(type default)
			)
			(layer "B.Fab")
		)
		(fp_line
			(start -0.67945 0.3048)
			(end -0.120396 0.3048)
			(stroke
				(width 0.1)
				(type default)
			)
			(layer "B.Fab")
		)
		(fp_line
			(start -0.67945 -0.3048)
			(end -0.67945 0.3048)
			(stroke
				(width 0.1)
				(type default)
			)
			(layer "B.Fab")
		)
		(pad "1" smd circle
			(at 0.40005 0)
			(size 0 0)
			(layers "B.Cu" "B.Mask" "B.Paste")
			(net "P3V3_AUX")
		)
		(pad "2" smd circle
			(at -0.40005 0)
			(size 0 0)
			(layers "B.Cu" "B.Mask" "B.Paste")
			(net "GND")
		)
	)
	(footprint ""
		(layer "B.Cu")
		(at 26.67 -90.805 180)
		(property "Reference" "C160"
			(at 0 0 0)
			(layer "B.SilkS")
			(hide yes)
			(effects
				(font
					(size 1.27 1.27)
				)
				(justify mirror)
			)
		)
		(property "Value" ""
			(at 0 0 0)
			(layer "B.Fab")
			(effects
				(font
					(size 1.27 1.27)
				)
				(justify mirror)
			)
		)
		(duplicate_pad_numbers_are_jumpers no)
		(fp_line
			(start 0.69215 0.2921)
			(end 0.69215 -0.2921)
			(stroke
				(width 0.1524)
				(type default)
			)
			(layer "B.SilkS")
		)
		(fp_line
			(start 0.69215 -0.2921)
			(end -0.69215 -0.2921)
			(stroke
				(width 0.1524)
				(type default)
			)
			(layer "B.SilkS")
		)
		(fp_line
			(start -0.69215 0.2921)
			(end 0.69215 0.2921)
			(stroke
				(width 0.1524)
				(type default)
			)
			(layer "B.SilkS")
		)
		(fp_line
			(start -0.69215 -0.2921)
			(end -0.69215 0.2921)
			(stroke
				(width 0.1524)
				(type default)
			)
			(layer "B.SilkS")
		)
		(fp_line
			(start 0.51435 0.2794)
			(end 0.51435 -0.2794)
			(stroke
				(width 0.1)
				(type default)
			)
			(layer "B.Fab")
		)
		(fp_line
			(start 0.51435 -0.2794)
			(end -0.51435 -0.2794)
			(stroke
				(width 0.1)
				(type default)
			)
			(layer "B.Fab")
		)
		(fp_line
			(start -0.51435 0.2794)
			(end 0.51435 0.2794)
			(stroke
				(width 0.1)
				(type default)
			)
			(layer "B.Fab")
		)
		(fp_line
			(start -0.51435 -0.2794)
			(end -0.51435 0.2794)
			(stroke
				(width 0.1)
				(type default)
			)
			(layer "B.Fab")
		)
		(pad "1" smd circle
			(at 0.40005 0)
			(size 0 0)
			(layers "B.Cu" "B.Mask" "B.Paste")
			(net "VCCIO5")
		)
		(pad "2" smd circle
			(at -0.40005 0)
			(size 0 0)
			(layers "B.Cu" "B.Mask" "B.Paste")
			(net "GND")
		)
		(zone
			(layer "B.Cu")
			(hatch none 0.5)
			(connect_pads
				(clearance 0)
			)
			(min_thickness 0.25)
			(keepout
				(tracks not_allowed)
				(vias allowed)
				(pads allowed)
				(copperpour not_allowed)
				(footprints allowed)
			)
			(placement
				(enabled no)
				(sheetname "")
			)
			(fill
				(thermal_gap 0.5)
				(thermal_bridge_width 0.5)
				(island_removal_mode 0)
			)
			(polygon
				(pts
					(xy 26.4795 -90.89263) (xy 26.57094 -90.950796) (xy 26.77033 -90.950796) (xy 26.8605 -90.89263)
					(xy 26.8605 -90.71737) (xy 26.77033 -90.65895) (xy 26.57094 -90.65895) (xy 26.4795 -90.717116)
				)
			)
		)
	)
	(footprint ""
		(layer "B.Cu")
		(at 30.31998 -88.97112 90)
		(property "Reference" "R767"
			(at 0 0 90)
			(layer "B.SilkS")
			(hide yes)
			(effects
				(font
					(size 1.27 1.27)
				)
				(justify mirror)
			)
		)
		(property "Value" ""
			(at 0 0 90)
			(layer "B.Fab")
			(effects
				(font
					(size 1.27 1.27)
				)
				(justify mirror)
			)
		)
		(duplicate_pad_numbers_are_jumpers no)
		(fp_line
			(start 0.7874 -0.4064)
			(end -0.7874 -0.4064)
			(stroke
				(width 0.1524)
				(type default)
			)
			(layer "B.SilkS")
		)
		(fp_line
			(start -0.7874 -0.4064)
			(end -0.7874 0.4064)
			(stroke
				(width 0.1524)
				(type default)
			)
			(layer "B.SilkS")
		)
		(fp_line
			(start 0.7874 0.4064)
			(end 0.7874 -0.4064)
			(stroke
				(width 0.1524)
				(type default)
			)
			(layer "B.SilkS")
		)
		(fp_line
			(start -0.7874 0.4064)
			(end 0.7874 0.4064)
			(stroke
				(width 0.1524)
				(type default)
			)
			(layer "B.SilkS")
		)
		(fp_line
			(start 0.67945 -0.305054)
			(end 0.12065 -0.305054)
			(stroke
				(width 0.1)
				(type default)
			)
			(layer "B.Fab")
		)
		(fp_line
			(start 0.12065 -0.305054)
			(end 0.12065 -0.2794)
			(stroke
				(width 0.1)
				(type default)
			)
			(layer "B.Fab")
		)
		(fp_line
			(start -0.12065 -0.3048)
			(end -0.67945 -0.3048)
			(stroke
				(width 0.1)
				(type default)
			)
			(layer "B.Fab")
		)
		(fp_line
			(start -0.67945 -0.3048)
			(end -0.67945 0.3048)
			(stroke
				(width 0.1)
				(type default)
			)
			(layer "B.Fab")
		)
		(fp_line
			(start 0.12065 -0.2794)
			(end -0.12065 -0.2794)
			(stroke
				(width 0.1)
				(type default)
			)
			(layer "B.Fab")
		)
		(fp_line
			(start -0.12065 -0.2794)
			(end -0.12065 -0.3048)
			(stroke
				(width 0.1)
				(type default)
			)
			(layer "B.Fab")
		)
		(fp_line
			(start 0.12065 0.2794)
			(end 0.12065 0.3048)
			(stroke
				(width 0.1)
				(type default)
			)
			(layer "B.Fab")
		)
		(fp_line
			(start -0.120396 0.2794)
			(end 0.12065 0.2794)
			(stroke
				(width 0.1)
				(type default)
			)
			(layer "B.Fab")
		)
		(fp_line
			(start 0.67945 0.3048)
			(end 0.67945 -0.305054)
			(stroke
				(width 0.1)
				(type default)
			)
			(layer "B.Fab")
		)
		(fp_line
			(start 0.12065 0.3048)
			(end 0.67945 0.3048)
			(stroke
				(width 0.1)
				(type default)
			)
			(layer "B.Fab")
		)
		(fp_line
			(start -0.120396 0.3048)
			(end -0.120396 0.2794)
			(stroke
				(width 0.1)
				(type default)
			)
			(layer "B.Fab")
		)
		(fp_line
			(start -0.67945 0.3048)
			(end -0.120396 0.3048)
			(stroke
				(width 0.1)
				(type default)
			)
			(layer "B.Fab")
		)
		(pad "1" smd circle
			(at 0.40005 0 270)
			(size 0 0)
			(layers "B.Cu" "B.Mask" "B.Paste")
			(net "FM_TPM_PRSNT_0_N")
		)
		(pad "2" smd circle
			(at -0.40005 0 270)
			(size 0 0)
			(layers "B.Cu" "B.Mask" "B.Paste")
			(net "FM_TPM_PRSNT_0_R_N")
		)
	)
	(footprint ""
		(layer "B.Cu")
		(at 114.554 -106.68 -90)
		(property "Reference" "X7"
			(at 2.19837 1.2192 0)
			(unlocked yes)
			(layer "B.SilkS")
			(effects
				(font
					(size 0.7874 0.5842)
					(thickness 0.1524)
				)
				(justify left mirror)
			)
		)
		(property "Value" ""
			(at 0 0 90)
			(layer "B.Fab")
			(effects
				(font
					(size 1.27 1.27)
				)
				(justify mirror)
			)
		)
		(property "Device Type" "TP_TDR_4P_FTS_TH-TP_TDR_4P_DIPA"
			(at -1.30175 1.27 180)
			(unlocked yes)
			(layer "B.Fab")
			(hide yes)
			(effects
				(font
					(size 0.635 0.4064)
					(thickness 0.1524)
				)
				(justify mirror)
			)
		)
		(property "User Part Number" "N_A"
			(at -1.30175 1.27 180)
			(unlocked yes)
			(layer "Cmts.User")
			(hide yes)
			(effects
				(font
					(size 0.635 0.4064)
					(thickness 0.1524)
				)
				(justify mirror)
			)
		)
		(duplicate_pad_numbers_are_jumpers no)
		(fp_line
			(start -2.54 3.81)
			(end -2.54 3.6703)
			(stroke
				(width 0.1524)
				(type default)
			)
			(layer "B.SilkS")
		)
		(fp_line
			(start 0 3.81)
			(end -2.54 3.81)
			(stroke
				(width 0.1524)
				(type default)
			)
			(layer "B.SilkS")
		)
		(fp_line
			(start 0 3.175)
			(end 0 3.81)
			(stroke
				(width 0.1524)
				(type default)
			)
			(layer "B.SilkS")
		)
		(fp_line
			(start -2.54 1.4097)
			(end -2.54 1.1303)
			(stroke
				(width 0.1524)
				(type default)
			)
			(layer "B.SilkS")
		)
		(fp_line
			(start 0 0.635)
			(end 0 1.905)
			(stroke
				(width 0.1524)
				(type default)
			)
			(layer "B.SilkS")
		)
		(fp_line
			(start -2.54 -1.1303)
			(end -2.54 -1.27)
			(stroke
				(width 0.1524)
				(type default)
			)
			(layer "B.SilkS")
		)
		(fp_line
			(start -2.54 -1.27)
			(end 0 -1.27)
			(stroke
				(width 0.1524)
				(type default)
			)
			(layer "B.SilkS")
		)
		(fp_line
			(start 0 -1.27)
			(end 0 -0.635)
			(stroke
				(width 0.1524)
				(type default)
			)
			(layer "B.SilkS")
		)
		(fp_poly
			(pts
				(xy 0.761746 0) (xy 2.285746 -0.762) (xy 2.285746 0.762)
			)
			(stroke
				(width 0)
				(type default)
			)
			(fill yes)
			(layer "B.SilkS")
		)
		(fp_line
			(start -2.54 3.81)
			(end -2.54 -1.27)
			(stroke
				(width 0.1)
				(type default)
			)
			(layer "B.Fab")
		)
		(fp_line
			(start 0 3.81)
			(end -2.54 3.81)
			(stroke
				(width 0.1)
				(type default)
			)
			(layer "B.Fab")
		)
		(fp_line
			(start -2.54 -1.27)
			(end 0 -1.27)
			(stroke
				(width 0.1)
				(type default)
			)
			(layer "B.Fab")
		)
		(fp_line
			(start 0 -1.27)
			(end 0 3.81)
			(stroke
				(width 0.1)
				(type default)
			)
			(layer "B.Fab")
		)
		(fp_poly
			(pts
				(xy 0.761746 0) (xy 2.285746 -0.762) (xy 2.285746 0.762)
			)
			(stroke
				(width 0)
				(type default)
			)
			(fill yes)
			(layer "B.Fab")
		)
		(pad "1" thru_hole circle
			(at 0 0 90)
			(size 1.0033 1.0033)
			(drill 0.249936)
			(layers "*.Cu" "*.Mask")
			(remove_unused_layers no)
			(net "TDR_DIFF_85_TOP_DN")
			(clearance 0.10795)
			(padstack
				(mode front_inner_back)
				(layer "Inner"
					(shape circle)
					(size 0.8001 0.8001)
					(clearance 0.1524)
				)
				(layer "B.Cu"
					(shape circle)
					(size 1.0033 1.0033)
					(thermal_gap 0.10795)
					(clearance 0.10795)
				)
			)
		)
		(pad "2" thru_hole circle
			(at -2.54 0 90)
			(size 1.9939 1.9939)
			(drill 0.249936)
			(layers "*.Cu" "*.Mask")
			(remove_unused_layers no)
			(net "GND_P1")
			(clearance 0.10795)
			(padstack
				(mode front_inner_back)
				(layer "Inner"
					(shape circle)
					(size 0.8001 0.8001)
					(clearance 0.1524)
				)
				(layer "B.Cu"
					(shape circle)
					(size 1.9939 1.9939)
					(thermal_gap 0.10795)
					(clearance 0.10795)
				)
			)
		)
		(pad "3" thru_hole circle
			(at -2.54 2.54 90)
			(size 1.9939 1.9939)
			(drill 0.249936)
			(layers "*.Cu" "*.Mask")
			(remove_unused_layers no)
			(net "GND_P1")
			(clearance 0.10795)
			(padstack
				(mode front_inner_back)
				(layer "Inner"
					(shape circle)
					(size 0.8001 0.8001)
					(clearance 0.1524)
				)
				(layer "B.Cu"
					(shape circle)
					(size 1.9939 1.9939)
					(thermal_gap 0.10795)
					(clearance 0.10795)
				)
			)
		)
		(pad "4" thru_hole circle
			(at 0 2.54 90)
			(size 1.0033 1.0033)
			(drill 0.249936)
			(layers "*.Cu" "*.Mask")
			(remove_unused_layers no)
			(net "TDR_DIFF_85_TOP_DP")
			(clearance 0.10795)
			(padstack
				(mode front_inner_back)
				(layer "Inner"
					(shape circle)
					(size 0.8001 0.8001)
					(clearance 0.1524)
				)
				(layer "B.Cu"
					(shape circle)
					(size 1.0033 1.0033)
					(thermal_gap 0.10795)
					(clearance 0.10795)
				)
			)
		)
	)
	(footprint ""
		(layer "B.Cu")
		(at 51.2445 -94.1705 180)
		(property "Reference" "R95"
			(at 0 0 0)
			(layer "B.SilkS")
			(hide yes)
			(effects
				(font
					(size 1.27 1.27)
				)
				(justify mirror)
			)
		)
		(property "Value" ""
			(at 0 0 0)
			(layer "B.Fab")
			(effects
				(font
					(size 1.27 1.27)
				)
				(justify mirror)
			)
		)
		(duplicate_pad_numbers_are_jumpers no)
		(fp_line
			(start 0.7874 0.4064)
			(end 0.7874 -0.4064)
			(stroke
				(width 0.1524)
				(type default)
			)
			(layer "B.SilkS")
		)
		(fp_line
			(start 0.7874 -0.4064)
			(end -0.7874 -0.4064)
			(stroke
				(width 0.1524)
				(type default)
			)
			(layer "B.SilkS")
		)
		(fp_line
			(start -0.7874 0.4064)
			(end 0.7874 0.4064)
			(stroke
				(width 0.1524)
				(type default)
			)
			(layer "B.SilkS")
		)
		(fp_line
			(start -0.7874 -0.4064)
			(end -0.7874 0.4064)
			(stroke
				(width 0.1524)
				(type default)
			)
			(layer "B.SilkS")
		)
		(fp_line
			(start 0.67945 0.3048)
			(end 0.67945 -0.305054)
			(stroke
				(width 0.1)
				(type default)
			)
			(layer "B.Fab")
		)
		(fp_line
			(start 0.67945 -0.305054)
			(end 0.12065 -0.305054)
			(stroke
				(width 0.1)
				(type default)
			)
			(layer "B.Fab")
		)
		(fp_line
			(start 0.12065 0.3048)
			(end 0.67945 0.3048)
			(stroke
				(width 0.1)
				(type default)
			)
			(layer "B.Fab")
		)
		(fp_line
			(start 0.12065 0.2794)
			(end 0.12065 0.3048)
			(stroke
				(width 0.1)
				(type default)
			)
			(layer "B.Fab")
		)
		(fp_line
			(start 0.12065 -0.2794)
			(end -0.12065 -0.2794)
			(stroke
				(width 0.1)
				(type default)
			)
			(layer "B.Fab")
		)
		(fp_line
			(start 0.12065 -0.305054)
			(end 0.12065 -0.2794)
			(stroke
				(width 0.1)
				(type default)
			)
			(layer "B.Fab")
		)
		(fp_line
			(start -0.120396 0.3048)
			(end -0.120396 0.2794)
			(stroke
				(width 0.1)
				(type default)
			)
			(layer "B.Fab")
		)
		(fp_line
			(start -0.120396 0.2794)
			(end 0.12065 0.2794)
			(stroke
				(width 0.1)
				(type default)
			)
			(layer "B.Fab")
		)
		(fp_line
			(start -0.12065 -0.2794)
			(end -0.12065 -0.3048)
			(stroke
				(width 0.1)
				(type default)
			)
			(layer "B.Fab")
		)
		(fp_line
			(start -0.12065 -0.3048)
			(end -0.67945 -0.3048)
			(stroke
				(width 0.1)
				(type default)
			)
			(layer "B.Fab")
		)
		(fp_line
			(start -0.67945 0.3048)
			(end -0.120396 0.3048)
			(stroke
				(width 0.1)
				(type default)
			)
			(layer "B.Fab")
		)
		(fp_line
			(start -0.67945 -0.3048)
			(end -0.67945 0.3048)
			(stroke
				(width 0.1)
				(type default)
			)
			(layer "B.Fab")
		)
		(pad "1" smd circle
			(at 0.40005 0)
			(size 0 0)
			(layers "B.Cu" "B.Mask" "B.Paste")
			(net "SMB_DEBUG_AUX_LVC3_USB_SDA")
		)
		(pad "2" smd circle
			(at -0.40005 0)
			(size 0 0)
			(layers "B.Cu" "B.Mask" "B.Paste")
			(net "SMB_DEBUG_AUX_LVC3_USB_R3_SDA")
		)
	)
	(footprint ""
		(layer "B.Cu")
		(at 18.259298 -89.18702 180)
		(property "Reference" "C283"
			(at 0 0 0)
			(layer "B.SilkS")
			(hide yes)
			(effects
				(font
					(size 1.27 1.27)
				)
				(justify mirror)
			)
		)
		(property "Value" ""
			(at 0 0 0)
			(layer "B.Fab")
			(effects
				(font
					(size 1.27 1.27)
				)
				(justify mirror)
			)
		)
		(duplicate_pad_numbers_are_jumpers no)
		(fp_line
			(start 0.69215 0.2921)
			(end 0.69215 -0.2921)
			(stroke
				(width 0.1524)
				(type default)
			)
			(layer "B.SilkS")
		)
		(fp_line
			(start 0.69215 -0.2921)
			(end -0.69215 -0.2921)
			(stroke
				(width 0.1524)
				(type default)
			)
			(layer "B.SilkS")
		)
		(fp_line
			(start -0.69215 0.2921)
			(end 0.69215 0.2921)
			(stroke
				(width 0.1524)
				(type default)
			)
			(layer "B.SilkS")
		)
		(fp_line
			(start -0.69215 -0.2921)
			(end -0.69215 0.2921)
			(stroke
				(width 0.1524)
				(type default)
			)
			(layer "B.SilkS")
		)
		(fp_line
			(start 0.51435 0.2794)
			(end 0.51435 -0.2794)
			(stroke
				(width 0.1)
				(type default)
			)
			(layer "B.Fab")
		)
		(fp_line
			(start 0.51435 -0.2794)
			(end -0.51435 -0.2794)
			(stroke
				(width 0.1)
				(type default)
			)
			(layer "B.Fab")
		)
		(fp_line
			(start -0.51435 0.2794)
			(end 0.51435 0.2794)
			(stroke
				(width 0.1)
				(type default)
			)
			(layer "B.Fab")
		)
		(fp_line
			(start -0.51435 -0.2794)
			(end -0.51435 0.2794)
			(stroke
				(width 0.1)
				(type default)
			)
			(layer "B.Fab")
		)
		(pad "1" smd circle
			(at 0.40005 0)
			(size 0 0)
			(layers "B.Cu" "B.Mask" "B.Paste")
			(net "VCCIO0")
		)
		(pad "2" smd circle
			(at -0.40005 0)
			(size 0 0)
			(layers "B.Cu" "B.Mask" "B.Paste")
			(net "GND")
		)
		(zone
			(layer "B.Cu")
			(hatch none 0.5)
			(connect_pads
				(clearance 0)
			)
			(min_thickness 0.25)
			(keepout
				(tracks not_allowed)
				(vias allowed)
				(pads allowed)
				(copperpour not_allowed)
				(footprints allowed)
			)
			(placement
				(enabled no)
				(sheetname "")
			)
			(fill
				(thermal_gap 0.5)
				(thermal_bridge_width 0.5)
				(island_removal_mode 0)
			)
			(polygon
				(pts
					(xy 18.068798 -89.27465) (xy 18.160238 -89.332816) (xy 18.359628 -89.332816) (xy 18.449798 -89.27465)
					(xy 18.449798 -89.09939) (xy 18.359628 -89.04097) (xy 18.160238 -89.04097) (xy 18.068798 -89.099136)
				)
			)
		)
	)
)
